# BASEBOARD_FAB2 (Tioga Pass) — schematic netlist excerpt (pin names and nets, part order shuffled) for the footprints in the layout excerpt that follows; sources: Cadence DE-HDL packaged netlist, KiCad conversion of Wiwynn_Tioga_Pass_MB.brd

Q8W1  NPN_DUAL  MBT3904 XSTR  pkg SSOPLF  page 89
  E(0)  = GND
  B(0)  = IRQ_DIMM_SAVE_LVT3_CPU1
  C(0)  = IRQ_DIMM_SAVE_LVT3_CPU1
  E(0)  = GND
  B(0)  = IRQ_DIMM_SAVE_CPU1_R_N
  C(0)  = IRQ_DIMM_SAVE_LVT3_N

R1M20  RES  1.00K 1% CHIP  pkg 0402  page 113 : A = P1V8_MCP_CPU0 ; B = JTAG_MCP_MUX_TDI
R3P35  RES  0.0 5% CHIP  pkg 0402  page 190 : A = RST_CPU1_LVC3_R1_N ; B = RST_CPU1_LVC3_N

(kicad_pcb
	(version 20260206)
	(generator "pcbnew")
	(generator_version "10.0")
	(general
		(thickness 1.6)
		(legacy_teardrops no)
	)
	(paper "A4")
	(title_block
		(title "Wiwynn_Tioga_Pass_MB.brd")
		(comment 1 "Tioga Pass / footprints 4357-4359 of 4770")
	)
	(layers
		(0 "F.Cu" signal "TOP")
		(4 "In1.Cu" signal "L2GND")
		(6 "In2.Cu" signal "L3")
		(8 "In3.Cu" signal "L4GND")
		(10 "In4.Cu" signal "L5")
		(12 "In5.Cu" signal "L6GND")
		(14 "In6.Cu" signal "L7VCC")
		(16 "In7.Cu" signal "L8VCC")
		(18 "In8.Cu" signal "L9GND")
		(20 "In9.Cu" signal "L10")
		(22 "In10.Cu" signal "L11GND")
		(24 "In11.Cu" signal "L12")
		(26 "In12.Cu" signal "L13GND")
		(2 "B.Cu" signal "BOTTOM")
		(9 "F.Adhes" user "F.Adhesive")
		(11 "B.Adhes" user "B.Adhesive")
		(13 "F.Paste" user "Package Geometry/Pastemask Top")
		(15 "B.Paste" user "Package Geometry/Pastemask Bottom")
		(5 "F.SilkS" user "Ref Des/Silkscreen Top")
		(7 "B.SilkS" user "Ref Des/Silkscreen Bottom")
		(1 "F.Mask" user "Board Geometry/Soldermask Top")
		(3 "B.Mask" user "Board Geometry/Soldermask Bottom")
		(17 "Dwgs.User" user "User.Drawings")
		(19 "Cmts.User" user "User.Comments")
		(21 "Eco1.User" user "User.Eco1")
		(23 "Eco2.User" user "User.Eco2")
		(25 "Edge.Cuts" user "Board Geometry/Outline")
		(27 "Margin" user)
		(31 "F.CrtYd" user "Package Geometry/Place Bound Top")
		(29 "B.CrtYd" user "Package Geometry/Place Bound Bottom")
		(35 "F.Fab" user "Ref Des/Assembly Top")
		(33 "B.Fab" user "Ref Des/Assembly Bottom")
	)
	(footprint ""
		(layer "B.Cu")
		(at 314.760102 -29.511752 90)
		(property "Reference" "Q8W1"
			(at 0 -1.2065 90)
			(unlocked yes)
			(layer "B.SilkS")
			(effects
				(font
					(size 1.27 0.9652)
					(thickness 0.1524)
				)
				(justify left mirror)
			)
		)
		(property "Value" ""
			(at 0 0 90)
			(layer "B.Fab")
			(effects
				(font
					(size 1.27 1.27)
				)
				(justify mirror)
			)
		)
		(duplicate_pad_numbers_are_jumpers no)
		(fp_circle
			(center 0.603758 -0.604266)
			(end 0.603758 -0.477266)
			(stroke
				(width 0.254)
				(type default)
			)
			(fill no)
			(layer "B.SilkS")
		)
		(fp_poly
			(pts
				(xy -0.21463 -0.450088) (xy -1.56337 -0.450088) (xy -1.56337 1.75006) (xy -0.21463 1.75006)
			)
			(stroke
				(width 0)
				(type default)
			)
			(fill no)
			(layer "B.CrtYd")
		)
		(fp_line
			(start -0.21463 -0.450088)
			(end -1.56337 -0.450088)
			(stroke
				(width 0.1)
				(type default)
			)
			(layer "B.Fab")
		)
		(fp_line
			(start -1.56337 -0.450088)
			(end -1.56337 1.75006)
			(stroke
				(width 0.1)
				(type default)
			)
			(layer "B.Fab")
		)
		(fp_line
			(start -0.21463 1.75006)
			(end -0.21463 -0.450088)
			(stroke
				(width 0.1)
				(type default)
			)
			(layer "B.Fab")
		)
		(fp_line
			(start -1.56337 1.75006)
			(end -0.21463 1.75006)
			(stroke
				(width 0.1)
				(type default)
			)
			(layer "B.Fab")
		)
		(fp_circle
			(center 0.848614 -0.6477)
			(end 0.848614 -0.5207)
			(stroke
				(width 0.254)
				(type default)
			)
			(fill no)
			(layer "B.Fab")
		)
		(pad "1" smd rect
			(at 0 0 270)
			(size 1.016 0.381)
			(layers "B.Cu" "B.Mask" "B.Paste")
			(net "GND")
		)
		(pad "2" smd rect
			(at 0 0.649986 270)
			(size 1.016 0.381)
			(layers "B.Cu" "B.Mask" "B.Paste")
			(net "IRQ_DIMM_SAVE_LVT3_CPU1")
		)
		(pad "3" smd rect
			(at 0 1.299972 270)
			(size 1.016 0.381)
			(layers "B.Cu" "B.Mask" "B.Paste")
			(net "IRQ_DIMM_SAVE_LVT3_CPU1")
		)
		(pad "4" smd rect
			(at -1.778 1.299972 270)
			(size 1.016 0.381)
			(layers "B.Cu" "B.Mask" "B.Paste")
			(net "GND")
		)
		(pad "5" smd rect
			(at -1.778 0.649986 270)
			(size 1.016 0.381)
			(layers "B.Cu" "B.Mask" "B.Paste")
			(net "IRQ_DIMM_SAVE_CPU1_R_N")
		)
		(pad "6" smd rect
			(at -1.778 0 270)
			(size 1.016 0.381)
			(layers "B.Cu" "B.Mask" "B.Paste")
			(net "IRQ_DIMM_SAVE_LVT3_N")
		)
	)
	(footprint ""
		(layer "B.Cu")
		(at 353.6315 -74.549 -90)
		(property "Reference" "R3P35"
			(at 0 0 90)
			(layer "B.SilkS")
			(hide yes)
			(effects
				(font
					(size 1.27 1.27)
				)
				(justify mirror)
			)
		)
		(property "Value" ""
			(at 0 0 90)
			(layer "B.Fab")
			(effects
				(font
					(size 1.27 1.27)
				)
				(justify mirror)
			)
		)
		(duplicate_pad_numbers_are_jumpers no)
		(fp_poly
			(pts
				(xy 0.2794 -0.1016) (xy -0.2794 -0.1016) (xy -0.2794 0.9906) (xy 0.2794 0.9906)
			)
			(stroke
				(width 0)
				(type default)
			)
			(fill no)
			(layer "B.CrtYd")
		)
		(fp_line
			(start -0.2794 0.9906)
			(end -0.2794 -0.1016)
			(stroke
				(width 0.1)
				(type default)
			)
			(layer "B.Fab")
		)
		(fp_line
			(start 0.2794 0.9906)
			(end -0.2794 0.9906)
			(stroke
				(width 0.1)
				(type default)
			)
			(layer "B.Fab")
		)
		(fp_line
			(start -0.2794 -0.1016)
			(end 0.2794 -0.1016)
			(stroke
				(width 0.1)
				(type default)
			)
			(layer "B.Fab")
		)
		(fp_line
			(start 0.2794 -0.1016)
			(end 0.2794 0.9906)
			(stroke
				(width 0.1)
				(type default)
			)
			(layer "B.Fab")
		)
		(pad "1" smd rect
			(at 0 0 90)
			(size 0.508 0.508)
			(layers "B.Cu" "B.Mask" "B.Paste")
			(net "RST_CPU1_LVC3_R1_N")
		)
		(pad "2" smd rect
			(at 0 0.889 90)
			(size 0.508 0.508)
			(layers "B.Cu" "B.Mask" "B.Paste")
			(net "RST_CPU1_LVC3_N")
		)
		(zone
			(layer "B.Cu")
			(hatch none 0.5)
			(connect_pads
				(clearance 0)
			)
			(min_thickness 0.25)
			(keepout
				(tracks not_allowed)
				(vias allowed)
				(pads allowed)
				(copperpour not_allowed)
				(footprints allowed)
			)
			(placement
				(enabled no)
				(sheetname "")
			)
			(fill
				(thermal_gap 0.5)
				(thermal_bridge_width 0.5)
				(island_removal_mode 0)
			)
			(polygon
				(pts
					(xy 352.9965 -74.295) (xy 352.9965 -74.803) (xy 353.3775 -74.803) (xy 353.3775 -74.295)
				)
			)
		)
		(zone
			(layer "B.Cu")
			(hatch none 0.5)
			(connect_pads
				(clearance 0)
			)
			(min_thickness 0.25)
			(keepout
				(tracks allowed)
				(vias not_allowed)
				(pads allowed)
				(copperpour not_allowed)
				(footprints allowed)
			)
			(placement
				(enabled no)
				(sheetname "")
			)
			(fill
				(thermal_gap 0.5)
				(thermal_bridge_width 0.5)
				(island_removal_mode 0)
			)
			(polygon
				(pts
					(xy 353.3775 -74.295) (xy 353.3775 -74.803) (xy 352.9965 -74.803) (xy 352.9965 -74.295)
				)
			)
		)
	)
	(footprint ""
		(layer "B.Cu")
		(at 449.199 -131.318 -90)
		(property "Reference" "R1M20"
			(at 0 0 90)
			(layer "B.SilkS")
			(hide yes)
			(effects
				(font
					(size 1.27 1.27)
				)
				(justify mirror)
			)
		)
		(property "Value" ""
			(at 0 0 90)
			(layer "B.Fab")
			(effects
				(font
					(size 1.27 1.27)
				)
				(justify mirror)
			)
		)
		(duplicate_pad_numbers_are_jumpers no)
		(fp_poly
			(pts
				(xy 0.2794 -0.1016) (xy -0.2794 -0.1016) (xy -0.2794 0.9906) (xy 0.2794 0.9906)
			)
			(stroke
				(width 0)
				(type default)
			)
			(fill no)
			(layer "B.CrtYd")
		)
		(fp_line
			(start -0.2794 0.9906)
			(end -0.2794 -0.1016)
			(stroke
				(width 0.1)
				(type default)
			)
			(layer "B.Fab")
		)
		(fp_line
			(start 0.2794 0.9906)
			(end -0.2794 0.9906)
			(stroke
				(width 0.1)
				(type default)
			)
			(layer "B.Fab")
		)
		(fp_line
			(start -0.2794 -0.1016)
			(end 0.2794 -0.1016)
			(stroke
				(width 0.1)
				(type default)
			)
			(layer "B.Fab")
		)
		(fp_line
			(start 0.2794 -0.1016)
			(end 0.2794 0.9906)
			(stroke
				(width 0.1)
				(type default)
			)
			(layer "B.Fab")
		)
		(pad "1" smd rect
			(at 0 0 90)
			(size 0.508 0.508)
			(layers "B.Cu" "B.Mask" "B.Paste")
			(net "P1V8_MCP_CPU0")
		)
		(pad "2" smd rect
			(at 0 0.889 90)
			(size 0.508 0.508)
			(layers "B.Cu" "B.Mask" "B.Paste")
			(net "JTAG_MCP_MUX_TDI")
		)
		(zone
			(layer "B.Cu")
			(hatch none 0.5)
			(connect_pads
				(clearance 0)
			)
			(min_thickness 0.25)
			(keepout
				(tracks not_allowed)
				(vias allowed)
				(pads allowed)
				(copperpour not_allowed)
				(footprints allowed)
			)
			(placement
				(enabled no)
				(sheetname "")
			)
			(fill
				(thermal_gap 0.5)
				(thermal_bridge_width 0.5)
				(island_removal_mode 0)
			)
			(polygon
				(pts
					(xy 448.564 -131.064) (xy 448.564 -131.572) (xy 448.945 -131.572) (xy 448.945 -131.064)
				)
			)
		)
		(zone
			(layer "B.Cu")
			(hatch none 0.5)
			(connect_pads
				(clearance 0)
			)
			(min_thickness 0.25)
			(keepout
				(tracks allowed)
				(vias not_allowed)
				(pads allowed)
				(copperpour not_allowed)
				(footprints allowed)
			)
			(placement
				(enabled no)
				(sheetname "")
			)
			(fill
				(thermal_gap 0.5)
				(thermal_bridge_width 0.5)
				(island_removal_mode 0)
			)
			(polygon
				(pts
					(xy 448.945 -131.064) (xy 448.945 -131.572) (xy 448.564 -131.572) (xy 448.564 -131.064)
				)
			)
		)
	)
)
